(kicad_pcb
	(version 20260206)
	(generator "pcbnew")
	(generator_version "10.0")
	(general
		(thickness 1.6)
		(legacy_teardrops no)
	)
	(paper "A4")
	(title_block
		(title "01162023_DA0F0TEBIF0_F0T_Expander_BD_F_brd_V02_OCP.brd")
		(comment 1 "Grand Teton / footprints 417-424 of 9728")
	)
	(layers
		(0 "F.Cu" signal "TOP")
		(4 "In1.Cu" signal "GND")
		(6 "In2.Cu" signal "VCC")
		(8 "In3.Cu" signal "VCC1")
		(10 "In4.Cu" signal "GND1")
		(12 "In5.Cu" signal "IN1")
		(14 "In6.Cu" signal "GND2")
		(16 "In7.Cu" signal "IN2")
		(18 "In8.Cu" signal "GND3")
		(20 "In9.Cu" signal "IN3")
		(22 "In10.Cu" signal "GND4")
		(24 "In11.Cu" signal "IN4")
		(26 "In12.Cu" signal "GND5")
		(28 "In13.Cu" signal "IN5")
		(30 "In14.Cu" signal "GND6")
		(32 "In15.Cu" signal "IN6")
		(34 "In16.Cu" signal "GND7")
		(2 "B.Cu" signal "BOTTOM")
		(9 "F.Adhes" user "F.Adhesive")
		(11 "B.Adhes" user "B.Adhesive")
		(13 "F.Paste" user "Package Geometry/Pastemask Top")
		(15 "B.Paste" user "Package Geometry/Pastemask Bottom")
		(5 "F.SilkS" user "Ref Des/Silkscreen Top")
		(7 "B.SilkS" user "Ref Des/Silkscreen Bottom")
		(1 "F.Mask" user "Board Geometry/Soldermask Top")
		(3 "B.Mask" user "Board Geometry/Soldermask Bottom")
		(17 "Dwgs.User" user "User.Drawings")
		(19 "Cmts.User" user "User.Comments")
		(21 "Eco1.User" user "User.Eco1")
		(23 "Eco2.User" user "User.Eco2")
		(25 "Edge.Cuts" user "Board Geometry/Outline")
		(27 "Margin" user)
		(31 "F.CrtYd" user "Package Geometry/Place Bound Top")
		(29 "B.CrtYd" user "Package Geometry/Place Bound Bottom")
		(35 "F.Fab" user "Ref Des/Assembly Top")
		(33 "B.Fab" user "Ref Des/Assembly Bottom")
	)
	(footprint ""
		(layer "F.Cu")
		(at 17.947132 -55.63489 90)
		(property "Reference" "PC357"
			(at 0 0 90)
			(layer "F.SilkS")
			(hide yes)
			(effects
				(font
					(size 1.27 1.27)
				)
			)
		)
		(property "Value" ""
			(at 0 0 90)
			(layer "F.Fab")
			(effects
				(font
					(size 1.27 1.27)
				)
			)
		)
		(duplicate_pad_numbers_are_jumpers no)
		(fp_line
			(start 1.524 -0.762)
			(end 1.524 0.762)
			(stroke
				(width 0.1524)
				(type default)
			)
			(layer "F.SilkS")
		)
		(fp_line
			(start -1.524 -0.762)
			(end 1.524 -0.762)
			(stroke
				(width 0.1524)
				(type default)
			)
			(layer "F.SilkS")
		)
		(fp_line
			(start 1.524 0.762)
			(end -1.524 0.762)
			(stroke
				(width 0.1524)
				(type default)
			)
			(layer "F.SilkS")
		)
		(fp_line
			(start -1.524 0.762)
			(end -1.524 -0.762)
			(stroke
				(width 0.1524)
				(type default)
			)
			(layer "F.SilkS")
		)
		(fp_line
			(start 1.1049 -0.724916)
			(end -1.1049 -0.724916)
			(stroke
				(width 0.1)
				(type default)
			)
			(layer "F.Fab")
		)
		(fp_line
			(start -1.1049 -0.724916)
			(end -1.1049 0.724916)
			(stroke
				(width 0.1)
				(type default)
			)
			(layer "F.Fab")
		)
		(fp_line
			(start 1.1049 0.724916)
			(end 1.1049 -0.724916)
			(stroke
				(width 0.1)
				(type default)
			)
			(layer "F.Fab")
		)
		(fp_line
			(start -1.1049 0.724916)
			(end 1.1049 0.724916)
			(stroke
				(width 0.1)
				(type default)
			)
			(layer "F.Fab")
		)
		(pad "1" smd rect
			(at -0.889 0 270)
			(size 1.016 1.27)
			(layers "F.Cu" "F.Mask" "F.Paste")
			(net "P12V_SSD0_R")
		)
		(pad "2" smd rect
			(at 0.889 0 270)
			(size 1.016 1.27)
			(layers "F.Cu" "F.Mask" "F.Paste")
			(net "GND")
		)
	)
	(footprint ""
		(layer "F.Cu")
		(at 270.990822 -142.892018)
		(property "Reference" "R234"
			(at 0 0 0)
			(layer "F.SilkS")
			(hide yes)
			(effects
				(font
					(size 1.27 1.27)
				)
			)
		)
		(property "Value" ""
			(at 0 0 0)
			(layer "F.Fab")
			(effects
				(font
					(size 1.27 1.27)
				)
			)
		)
		(duplicate_pad_numbers_are_jumpers no)
		(fp_line
			(start -0.7874 -0.4064)
			(end 0.7874 -0.4064)
			(stroke
				(width 0.1524)
				(type default)
			)
			(layer "F.SilkS")
		)
		(fp_line
			(start -0.7874 0.4064)
			(end -0.7874 -0.4064)
			(stroke
				(width 0.1524)
				(type default)
			)
			(layer "F.SilkS")
		)
		(fp_line
			(start 0.7874 -0.4064)
			(end 0.7874 0.4064)
			(stroke
				(width 0.1524)
				(type default)
			)
			(layer "F.SilkS")
		)
		(fp_line
			(start 0.7874 0.4064)
			(end -0.7874 0.4064)
			(stroke
				(width 0.1524)
				(type default)
			)
			(layer "F.SilkS")
		)
		(fp_line
			(start -0.67945 -0.305054)
			(end -0.12065 -0.305054)
			(stroke
				(width 0.1)
				(type default)
			)
			(layer "F.Fab")
		)
		(fp_line
			(start -0.67945 0.3048)
			(end -0.67945 -0.305054)
			(stroke
				(width 0.1)
				(type default)
			)
			(layer "F.Fab")
		)
		(fp_line
			(start -0.12065 -0.305054)
			(end -0.12065 -0.2794)
			(stroke
				(width 0.1)
				(type default)
			)
			(layer "F.Fab")
		)
		(fp_line
			(start -0.12065 -0.2794)
			(end 0.12065 -0.2794)
			(stroke
				(width 0.1)
				(type default)
			)
			(layer "F.Fab")
		)
		(fp_line
			(start -0.12065 0.2794)
			(end -0.12065 0.3048)
			(stroke
				(width 0.1)
				(type default)
			)
			(layer "F.Fab")
		)
		(fp_line
			(start -0.12065 0.3048)
			(end -0.67945 0.3048)
			(stroke
				(width 0.1)
				(type default)
			)
			(layer "F.Fab")
		)
		(fp_line
			(start 0.120396 0.2794)
			(end -0.12065 0.2794)
			(stroke
				(width 0.1)
				(type default)
			)
			(layer "F.Fab")
		)
		(fp_line
			(start 0.120396 0.3048)
			(end 0.120396 0.2794)
			(stroke
				(width 0.1)
				(type default)
			)
			(layer "F.Fab")
		)
		(fp_line
			(start 0.12065 -0.3048)
			(end 0.67945 -0.3048)
			(stroke
				(width 0.1)
				(type default)
			)
			(layer "F.Fab")
		)
		(fp_line
			(start 0.12065 -0.2794)
			(end 0.12065 -0.3048)
			(stroke
				(width 0.1)
				(type default)
			)
			(layer "F.Fab")
		)
		(fp_line
			(start 0.67945 -0.3048)
			(end 0.67945 0.3048)
			(stroke
				(width 0.1)
				(type default)
			)
			(layer "F.Fab")
		)
		(fp_line
			(start 0.67945 0.3048)
			(end 0.120396 0.3048)
			(stroke
				(width 0.1)
				(type default)
			)
			(layer "F.Fab")
		)
		(pad "1" smd circle
			(at -0.40005 0)
			(size 0 0)
			(layers "F.Cu" "F.Mask" "F.Paste")
			(net "NIC4_BIF0_N")
		)
		(pad "2" smd circle
			(at 0.40005 0)
			(size 0 0)
			(layers "F.Cu" "F.Mask" "F.Paste")
			(net "GND")
		)
	)
	(footprint ""
		(layer "F.Cu")
		(at 256.19329 -77.279754 90)
		(property "Reference" "R1065"
			(at 0 0 90)
			(layer "F.SilkS")
			(hide yes)
			(effects
				(font
					(size 1.27 1.27)
				)
			)
		)
		(property "Value" ""
			(at 0 0 90)
			(layer "F.Fab")
			(effects
				(font
					(size 1.27 1.27)
				)
			)
		)
		(duplicate_pad_numbers_are_jumpers no)
		(fp_line
			(start 0.7874 -0.4064)
			(end 0.7874 0.4064)
			(stroke
				(width 0.1524)
				(type default)
			)
			(layer "F.SilkS")
		)
		(fp_line
			(start -0.7874 -0.4064)
			(end 0.7874 -0.4064)
			(stroke
				(width 0.1524)
				(type default)
			)
			(layer "F.SilkS")
		)
		(fp_line
			(start 0.7874 0.4064)
			(end -0.7874 0.4064)
			(stroke
				(width 0.1524)
				(type default)
			)
			(layer "F.SilkS")
		)
		(fp_line
			(start -0.7874 0.4064)
			(end -0.7874 -0.4064)
			(stroke
				(width 0.1524)
				(type default)
			)
			(layer "F.SilkS")
		)
		(fp_line
			(start -0.12065 -0.305054)
			(end -0.12065 -0.2794)
			(stroke
				(width 0.1)
				(type default)
			)
			(layer "F.Fab")
		)
		(fp_line
			(start -0.67945 -0.305054)
			(end -0.12065 -0.305054)
			(stroke
				(width 0.1)
				(type default)
			)
			(layer "F.Fab")
		)
		(fp_line
			(start 0.67945 -0.3048)
			(end 0.67945 0.3048)
			(stroke
				(width 0.1)
				(type default)
			)
			(layer "F.Fab")
		)
		(fp_line
			(start 0.12065 -0.3048)
			(end 0.67945 -0.3048)
			(stroke
				(width 0.1)
				(type default)
			)
			(layer "F.Fab")
		)
		(fp_line
			(start 0.12065 -0.2794)
			(end 0.12065 -0.3048)
			(stroke
				(width 0.1)
				(type default)
			)
			(layer "F.Fab")
		)
		(fp_line
			(start -0.12065 -0.2794)
			(end 0.12065 -0.2794)
			(stroke
				(width 0.1)
				(type default)
			)
			(layer "F.Fab")
		)
		(fp_line
			(start 0.120396 0.2794)
			(end -0.12065 0.2794)
			(stroke
				(width 0.1)
				(type default)
			)
			(layer "F.Fab")
		)
		(fp_line
			(start -0.12065 0.2794)
			(end -0.12065 0.3048)
			(stroke
				(width 0.1)
				(type default)
			)
			(layer "F.Fab")
		)
		(fp_line
			(start 0.67945 0.3048)
			(end 0.120396 0.3048)
			(stroke
				(width 0.1)
				(type default)
			)
			(layer "F.Fab")
		)
		(fp_line
			(start 0.120396 0.3048)
			(end 0.120396 0.2794)
			(stroke
				(width 0.1)
				(type default)
			)
			(layer "F.Fab")
		)
		(fp_line
			(start -0.12065 0.3048)
			(end -0.67945 0.3048)
			(stroke
				(width 0.1)
				(type default)
			)
			(layer "F.Fab")
		)
		(fp_line
			(start -0.67945 0.3048)
			(end -0.67945 -0.305054)
			(stroke
				(width 0.1)
				(type default)
			)
			(layer "F.Fab")
		)
		(pad "1" smd circle
			(at -0.40005 0 90)
			(size 0 0)
			(layers "F.Cu" "F.Mask" "F.Paste")
			(net "GND")
		)
		(pad "2" smd circle
			(at 0.40005 0 90)
			(size 0 0)
			(layers "F.Cu" "F.Mask" "F.Paste")
			(net "FM_CLK_EN_R")
		)
	)
	(footprint ""
		(layer "F.Cu")
		(at 452.316596 -307.260752 90)
		(property "Reference" "PC277"
			(at 0 0 90)
			(layer "F.SilkS")
			(hide yes)
			(effects
				(font
					(size 1.27 1.27)
				)
			)
		)
		(property "Value" ""
			(at 0 0 90)
			(layer "F.Fab")
			(effects
				(font
					(size 1.27 1.27)
				)
			)
		)
		(duplicate_pad_numbers_are_jumpers no)
		(fp_line
			(start 0.7874 -0.4064)
			(end 0.7874 0.4064)
			(stroke
				(width 0.1524)
				(type default)
			)
			(layer "F.SilkS")
		)
		(fp_line
			(start -0.7874 -0.4064)
			(end 0.7874 -0.4064)
			(stroke
				(width 0.1524)
				(type default)
			)
			(layer "F.SilkS")
		)
		(fp_line
			(start 0.7874 0.4064)
			(end -0.7874 0.4064)
			(stroke
				(width 0.1524)
				(type default)
			)
			(layer "F.SilkS")
		)
		(fp_line
			(start -0.7874 0.4064)
			(end -0.7874 -0.4064)
			(stroke
				(width 0.1524)
				(type default)
			)
			(layer "F.SilkS")
		)
		(fp_line
			(start -0.12065 -0.305054)
			(end -0.12065 -0.2794)
			(stroke
				(width 0.1)
				(type default)
			)
			(layer "F.Fab")
		)
		(fp_line
			(start -0.67945 -0.305054)
			(end -0.12065 -0.305054)
			(stroke
				(width 0.1)
				(type default)
			)
			(layer "F.Fab")
		)
		(fp_line
			(start 0.67945 -0.3048)
			(end 0.67945 0.3048)
			(stroke
				(width 0.1)
				(type default)
			)
			(layer "F.Fab")
		)
		(fp_line
			(start 0.12065 -0.3048)
			(end 0.67945 -0.3048)
			(stroke
				(width 0.1)
				(type default)
			)
			(layer "F.Fab")
		)
		(fp_line
			(start 0.12065 -0.2794)
			(end 0.12065 -0.3048)
			(stroke
				(width 0.1)
				(type default)
			)
			(layer "F.Fab")
		)
		(fp_line
			(start -0.12065 -0.2794)
			(end 0.12065 -0.2794)
			(stroke
				(width 0.1)
				(type default)
			)
			(layer "F.Fab")
		)
		(fp_line
			(start 0.120396 0.2794)
			(end -0.12065 0.2794)
			(stroke
				(width 0.1)
				(type default)
			)
			(layer "F.Fab")
		)
		(fp_line
			(start -0.12065 0.2794)
			(end -0.12065 0.3048)
			(stroke
				(width 0.1)
				(type default)
			)
			(layer "F.Fab")
		)
		(fp_line
			(start 0.67945 0.3048)
			(end 0.120396 0.3048)
			(stroke
				(width 0.1)
				(type default)
			)
			(layer "F.Fab")
		)
		(fp_line
			(start 0.120396 0.3048)
			(end 0.120396 0.2794)
			(stroke
				(width 0.1)
				(type default)
			)
			(layer "F.Fab")
		)
		(fp_line
			(start -0.12065 0.3048)
			(end -0.67945 0.3048)
			(stroke
				(width 0.1)
				(type default)
			)
			(layer "F.Fab")
		)
		(fp_line
			(start -0.67945 0.3048)
			(end -0.67945 -0.305054)
			(stroke
				(width 0.1)
				(type default)
			)
			(layer "F.Fab")
		)
		(pad "1" smd circle
			(at -0.40005 0 90)
			(size 0 0)
			(layers "F.Cu" "F.Mask" "F.Paste")
			(net "P1V25_PEX3_VCC")
		)
		(pad "2" smd circle
			(at 0.40005 0 90)
			(size 0 0)
			(layers "F.Cu" "F.Mask" "F.Paste")
			(net "GND")
		)
	)
	(footprint ""
		(layer "F.Cu")
		(at 151.398478 -137.259314 -90)
		(property "Reference" "C883"
			(at 0 0 270)
			(layer "F.SilkS")
			(hide yes)
			(effects
				(font
					(size 1.27 1.27)
				)
			)
		)
		(property "Value" ""
			(at 0 0 270)
			(layer "F.Fab")
			(effects
				(font
					(size 1.27 1.27)
				)
			)
		)
		(duplicate_pad_numbers_are_jumpers no)
		(fp_line
			(start -0.7874 0.4064)
			(end -0.7874 -0.4064)
			(stroke
				(width 0.1524)
				(type default)
			)
			(layer "F.SilkS")
		)
		(fp_line
			(start 0.7874 0.4064)
			(end -0.7874 0.4064)
			(stroke
				(width 0.1524)
				(type default)
			)
			(layer "F.SilkS")
		)
		(fp_line
			(start -0.7874 -0.4064)
			(end 0.7874 -0.4064)
			(stroke
				(width 0.1524)
				(type default)
			)
			(layer "F.SilkS")
		)
		(fp_line
			(start 0.7874 -0.4064)
			(end 0.7874 0.4064)
			(stroke
				(width 0.1524)
				(type default)
			)
			(layer "F.SilkS")
		)
		(fp_line
			(start -0.67945 0.3048)
			(end -0.67945 -0.305054)
			(stroke
				(width 0.1)
				(type default)
			)
			(layer "F.Fab")
		)
		(fp_line
			(start -0.12065 0.3048)
			(end -0.67945 0.3048)
			(stroke
				(width 0.1)
				(type default)
			)
			(layer "F.Fab")
		)
		(fp_line
			(start 0.120396 0.3048)
			(end 0.120396 0.2794)
			(stroke
				(width 0.1)
				(type default)
			)
			(layer "F.Fab")
		)
		(fp_line
			(start 0.67945 0.3048)
			(end 0.120396 0.3048)
			(stroke
				(width 0.1)
				(type default)
			)
			(layer "F.Fab")
		)
		(fp_line
			(start -0.12065 0.2794)
			(end -0.12065 0.3048)
			(stroke
				(width 0.1)
				(type default)
			)
			(layer "F.Fab")
		)
		(fp_line
			(start 0.120396 0.2794)
			(end -0.12065 0.2794)
			(stroke
				(width 0.1)
				(type default)
			)
			(layer "F.Fab")
		)
		(fp_line
			(start -0.12065 -0.2794)
			(end 0.12065 -0.2794)
			(stroke
				(width 0.1)
				(type default)
			)
			(layer "F.Fab")
		)
		(fp_line
			(start 0.12065 -0.2794)
			(end 0.12065 -0.3048)
			(stroke
				(width 0.1)
				(type default)
			)
			(layer "F.Fab")
		)
		(fp_line
			(start 0.12065 -0.3048)
			(end 0.67945 -0.3048)
			(stroke
				(width 0.1)
				(type default)
			)
			(layer "F.Fab")
		)
		(fp_line
			(start 0.67945 -0.3048)
			(end 0.67945 0.3048)
			(stroke
				(width 0.1)
				(type default)
			)
			(layer "F.Fab")
		)
		(fp_line
			(start -0.67945 -0.305054)
			(end -0.12065 -0.305054)
			(stroke
				(width 0.1)
				(type default)
			)
			(layer "F.Fab")
		)
		(fp_line
			(start -0.12065 -0.305054)
			(end -0.12065 -0.2794)
			(stroke
				(width 0.1)
				(type default)
			)
			(layer "F.Fab")
		)
		(pad "1" smd circle
			(at -0.40005 0 270)
			(size 0 0)
			(layers "F.Cu" "F.Mask" "F.Paste")
			(net "P3V3_NIC2")
		)
		(pad "2" smd circle
			(at 0.40005 0 270)
			(size 0 0)
			(layers "F.Cu" "F.Mask" "F.Paste")
			(net "GND")
		)
	)
	(footprint ""
		(layer "F.Cu")
		(at 24.482044 -37.025072)
		(property "Reference" "R5649"
			(at 0 0 0)
			(layer "F.SilkS")
			(hide yes)
			(effects
				(font
					(size 1.27 1.27)
				)
			)
		)
		(property "Value" ""
			(at 0 0 0)
			(layer "F.Fab")
			(effects
				(font
					(size 1.27 1.27)
				)
			)
		)
		(duplicate_pad_numbers_are_jumpers no)
		(fp_line
			(start -0.7874 -0.4064)
			(end 0.7874 -0.4064)
			(stroke
				(width 0.1524)
				(type default)
			)
			(layer "F.SilkS")
		)
		(fp_line
			(start -0.7874 0.4064)
			(end -0.7874 -0.4064)
			(stroke
				(width 0.1524)
				(type default)
			)
			(layer "F.SilkS")
		)
		(fp_line
			(start 0.7874 -0.4064)
			(end 0.7874 0.4064)
			(stroke
				(width 0.1524)
				(type default)
			)
			(layer "F.SilkS")
		)
		(fp_line
			(start 0.7874 0.4064)
			(end -0.7874 0.4064)
			(stroke
				(width 0.1524)
				(type default)
			)
			(layer "F.SilkS")
		)
		(fp_line
			(start -0.67945 -0.305054)
			(end -0.12065 -0.305054)
			(stroke
				(width 0.1)
				(type default)
			)
			(layer "F.Fab")
		)
		(fp_line
			(start -0.67945 0.3048)
			(end -0.67945 -0.305054)
			(stroke
				(width 0.1)
				(type default)
			)
			(layer "F.Fab")
		)
		(fp_line
			(start -0.12065 -0.305054)
			(end -0.12065 -0.2794)
			(stroke
				(width 0.1)
				(type default)
			)
			(layer "F.Fab")
		)
		(fp_line
			(start -0.12065 -0.2794)
			(end 0.12065 -0.2794)
			(stroke
				(width 0.1)
				(type default)
			)
			(layer "F.Fab")
		)
		(fp_line
			(start -0.12065 0.2794)
			(end -0.12065 0.3048)
			(stroke
				(width 0.1)
				(type default)
			)
			(layer "F.Fab")
		)
		(fp_line
			(start -0.12065 0.3048)
			(end -0.67945 0.3048)
			(stroke
				(width 0.1)
				(type default)
			)
			(layer "F.Fab")
		)
		(fp_line
			(start 0.120396 0.2794)
			(end -0.12065 0.2794)
			(stroke
				(width 0.1)
				(type default)
			)
			(layer "F.Fab")
		)
		(fp_line
			(start 0.120396 0.3048)
			(end 0.120396 0.2794)
			(stroke
				(width 0.1)
				(type default)
			)
			(layer "F.Fab")
		)
		(fp_line
			(start 0.12065 -0.3048)
			(end 0.67945 -0.3048)
			(stroke
				(width 0.1)
				(type default)
			)
			(layer "F.Fab")
		)
		(fp_line
			(start 0.12065 -0.2794)
			(end 0.12065 -0.3048)
			(stroke
				(width 0.1)
				(type default)
			)
			(layer "F.Fab")
		)
		(fp_line
			(start 0.67945 -0.3048)
			(end 0.67945 0.3048)
			(stroke
				(width 0.1)
				(type default)
			)
			(layer "F.Fab")
		)
		(fp_line
			(start 0.67945 0.3048)
			(end 0.120396 0.3048)
			(stroke
				(width 0.1)
				(type default)
			)
			(layer "F.Fab")
		)
		(pad "1" smd circle
			(at -0.40005 0)
			(size 0 0)
			(layers "F.Cu" "F.Mask" "F.Paste")
			(net "RST_SMB_SSD_R_N")
		)
		(pad "2" smd circle
			(at 0.40005 0)
			(size 0 0)
			(layers "F.Cu" "F.Mask" "F.Paste")
			(net "RST_SMB_SSD1_N")
		)
	)
	(footprint ""
		(layer "F.Cu")
		(at 471.057986 -527.794474 180)
		(property "Reference" "J57_12"
			(at -2.8448 -1.402334 0)
			(unlocked yes)
			(layer "B.SilkS")
			(effects
				(font
					(size 0.7874 0.5842)
					(thickness 0.1524)
				)
				(justify mirror)
			)
		)
		(property "Value" ""
			(at 0 0 180)
			(layer "F.Fab")
			(effects
				(font
					(size 1.27 1.27)
				)
			)
		)
		(duplicate_pad_numbers_are_jumpers no)
		(pad "1" thru_hole circle
			(at 0 0 180)
			(size 0.4572 0.4572)
			(drill 0.2032)
			(layers "*.Cu" "*.Mask")
			(remove_unused_layers no)
			(net "Net_2680")
			(clearance 0.127)
			(thermal_gap 0.127)
			(padstack
				(mode front_inner_back)
				(layer "Inner"
					(shape circle)
					(size 0.4572 0.4572)
					(clearance 0.127)
				)
				(layer "B.Cu"
					(shape circle)
					(size 0.508 0.508)
					(clearance 0.1016)
				)
			)
		)
	)
	(footprint ""
		(layer "F.Cu")
		(at 247.553988 -307.484272)
		(property "Reference" "PJ14"
			(at 0 0 0)
			(layer "F.SilkS")
			(hide yes)
			(effects
				(font
					(size 1.27 1.27)
				)
			)
		)
		(property "Value" ""
			(at 0 0 0)
			(layer "F.Fab")
			(effects
				(font
					(size 1.27 1.27)
				)
			)
		)
		(duplicate_pad_numbers_are_jumpers no)
		(pad "1" smd circle
			(at -0.40005 0 90)
			(size 0 0)
			(layers "F.Cu" "F.Mask" "F.Paste")
			(net "SH_P1V25_PEX2_FB_N")
		)
		(pad "2" smd rect
			(at 0.40005 0 180)
			(size 0.4572 0.508)
			(layers "F.Cu" "F.Mask" "F.Paste")
			(net "GND")
		)
		(zone
			(layer "F.Cu")
			(hatch none 0.5)
			(connect_pads
				(clearance 0)
			)
			(min_thickness 0.25)
			(keepout
				(tracks allowed)
				(vias not_allowed)
				(pads allowed)
				(copperpour not_allowed)
				(footprints allowed)
			)
			(placement
				(enabled no)
				(sheetname "")
			)
			(fill
				(thermal_gap 0.5)
				(thermal_bridge_width 0.5)
				(island_removal_mode 0)
			)
			(polygon
				(pts
					(xy 246.868188 -307.179472) (xy 248.239788 -307.179472) (xy 248.239788 -307.789072) (xy 246.868188 -307.789072)
				)
			)
		)
	)
)
